# T6G (Grand Teton) — schematic netlist excerpt (pin names and nets, part order shuffled) for the footprints in the layout excerpt that follows; sources: Cadence DE-HDL packaged netlist, KiCad conversion of 04192023_DAF0TMB3IC0_F0TG_MB_C_brd_V02_OCP.brd

J73  PICOPROBE_BXA  DELTA-L 4.0 EMPTY  pkg TRIANG_LAUNCH_3PXB  page 229
  \1_p\  = DELTA_L_85_5INCH_IN3_DN
  \2_n\  = DELTA_L_85_5INCH_IN3_DP
  \3_g\  = DELTA_L_GND_1

(kicad_pcb
	(version 20260206)
	(generator "pcbnew")
	(generator_version "10.0")
	(general
		(thickness 1.6)
		(legacy_teardrops no)
	)
	(paper "A4")
	(title_block
		(title "04192023_DAF0TMB3IC0_F0TG_MB_C_brd_V02_OCP.brd")
		(comment 1 "Grand Teton / footprints 577-577 of 8354")
	)
	(layers
		(0 "F.Cu" signal "TOP")
		(4 "In1.Cu" signal "GND")
		(6 "In2.Cu" signal "IN1")
		(8 "In3.Cu" signal "GND1")
		(10 "In4.Cu" signal "IN2")
		(12 "In5.Cu" signal "GND2")
		(14 "In6.Cu" signal "IN3")
		(16 "In7.Cu" signal "GND3")
		(18 "In8.Cu" signal "VCC")
		(20 "In9.Cu" signal "VCC1")
		(22 "In10.Cu" signal "GND4")
		(24 "In11.Cu" signal "IN4")
		(26 "In12.Cu" signal "GND5")
		(28 "In13.Cu" signal "IN5")
		(30 "In14.Cu" signal "GND6")
		(32 "In15.Cu" signal "IN6")
		(34 "In16.Cu" signal "GND7")
		(2 "B.Cu" signal "BOTTOM")
		(9 "F.Adhes" user "F.Adhesive")
		(11 "B.Adhes" user "B.Adhesive")
		(13 "F.Paste" user "Package Geometry/Pastemask Top")
		(15 "B.Paste" user "Package Geometry/Pastemask Bottom")
		(5 "F.SilkS" user "Ref Des/Silkscreen Top")
		(7 "B.SilkS" user "Ref Des/Silkscreen Bottom")
		(1 "F.Mask" user "Board Geometry/Soldermask Top")
		(3 "B.Mask" user "Board Geometry/Soldermask Bottom")
		(17 "Dwgs.User" user "User.Drawings")
		(19 "Cmts.User" user "User.Comments")
		(21 "Eco1.User" user "User.Eco1")
		(23 "Eco2.User" user "User.Eco2")
		(25 "Edge.Cuts" user "Board Geometry/Outline")
		(27 "Margin" user)
		(31 "F.CrtYd" user "Package Geometry/Place Bound Top")
		(29 "B.CrtYd" user "Package Geometry/Place Bound Bottom")
		(35 "F.Fab" user "Ref Des/Assembly Top")
		(33 "B.Fab" user "Ref Des/Assembly Bottom")
	)
	(footprint ""
		(layer "F.Cu")
		(at 314.965588 0.002794)
		(property "Reference" "J73"
			(at -4.473448 1.284732 90)
			(unlocked yes)
			(layer "F.SilkS")
			(effects
				(font
					(size 0.7874 0.5842)
					(thickness 0.1524)
				)
				(justify left)
			)
		)
		(property "Value" ""
			(at 0 0 0)
			(layer "F.Fab")
			(effects
				(font
					(size 1.27 1.27)
				)
			)
		)
		(duplicate_pad_numbers_are_jumpers no)
		(fp_line
			(start -1.2192 -2.06756)
			(end 1.2192 -2.06756)
			(stroke
				(width 0.1524)
				(type default)
			)
			(layer "F.SilkS")
		)
		(fp_line
			(start -1.2192 2.06756)
			(end -1.2192 -2.06756)
			(stroke
				(width 0.1524)
				(type default)
			)
			(layer "F.SilkS")
		)
		(fp_line
			(start 1.2192 -2.06756)
			(end 1.2192 2.06756)
			(stroke
				(width 0.1524)
				(type default)
			)
			(layer "F.SilkS")
		)
		(fp_line
			(start 1.2192 2.06756)
			(end -1.2192 2.06756)
			(stroke
				(width 0.1524)
				(type default)
			)
			(layer "F.SilkS")
		)
		(pad "" np_thru_hole circle
			(at -2.8829 -1.27 270)
			(size 1.0414 1.0414)
			(drill 1.0414)
			(layers "*.Cu" "*.Mask")
			(clearance 0.381)
			(thermal_gap 0.381)
		)
		(pad "" np_thru_hole circle
			(at -2.8829 1.27 270)
			(size 1.0414 1.0414)
			(drill 1.0414)
			(layers "*.Cu" "*.Mask")
			(clearance 0.381)
			(thermal_gap 0.381)
		)
		(pad "" np_thru_hole circle
			(at 3.4671 -1.27 270)
			(size 1.0414 1.0414)
			(drill 1.0414)
			(layers "*.Cu" "*.Mask")
			(clearance 0.381)
			(thermal_gap 0.381)
		)
		(pad "" np_thru_hole circle
			(at 3.4671 1.27 270)
			(size 1.0414 1.0414)
			(drill 1.0414)
			(layers "*.Cu" "*.Mask")
			(clearance 0.381)
			(thermal_gap 0.381)
		)
		(pad "1" smd rect
			(at 0.8255 -0.249936 270)
			(size 0.3048 0.508)
			(layers "F.Cu" "F.Mask" "F.Paste")
			(net "DELTA_L_85_5INCH_IN3_DN")
		)
		(pad "2" smd rect
			(at 0.8255 0.249936 270)
			(size 0.3048 0.508)
			(layers "F.Cu" "F.Mask" "F.Paste")
			(net "DELTA_L_85_5INCH_IN3_DP")
		)
		(pad "3" smd circle
			(at 0 0)
			(size 0 0)
			(layers "F.Cu" "F.Mask" "F.Paste")
			(net "DELTA_L_GND_1")
		)
		(zone
			(layer "F.Cu")
			(hatch none 0.5)
			(connect_pads
				(clearance 0)
			)
			(min_thickness 0.25)
			(keepout
				(tracks not_allowed)
				(vias allowed)
				(pads allowed)
				(copperpour not_allowed)
				(footprints allowed)
			)
			(placement
				(enabled no)
				(sheetname "")
			)
			(fill
				(thermal_gap 0.5)
				(thermal_bridge_width 0.5)
				(island_removal_mode 0)
			)
			(polygon
				(pts
					(xy 316.083188 -0.545846) (xy 316.083188 -0.450342) (xy 315.486288 -0.450342) (xy 315.486288 -0.043942)
					(xy 316.083188 -0.043942) (xy 316.083188 0.04953) (xy 315.486288 0.04953) (xy 315.486288 0.45593)
					(xy 316.083188 0.45593) (xy 316.083188 0.551434) (xy 315.384688 0.551434) (xy 315.384688 -0.545846)
				)
			)
		)
		(zone
			(layers "F.Cu" "B.Cu" "In1.Cu" "In2.Cu" "In3.Cu" "In4.Cu" "In5.Cu" "In6.Cu"
				"In7.Cu" "In8.Cu" "In9.Cu" "In10.Cu" "In11.Cu" "In12.Cu" "In13.Cu" "In14.Cu"
				"In15.Cu" "In16.Cu"
			)
			(hatch none 0.5)
			(connect_pads
				(clearance 0)
			)
			(min_thickness 0.25)
			(keepout
				(tracks not_allowed)
				(vias allowed)
				(pads allowed)
				(copperpour not_allowed)
				(footprints allowed)
			)
			(placement
				(enabled no)
				(sheetname "")
			)
			(fill
				(thermal_gap 0.5)
				(thermal_bridge_width 0.5)
				(island_removal_mode 0)
			)
			(polygon
				(pts
					(arc
						(start 313.009788 -1.267206)
						(mid 311.155588 -1.267206)
						(end 313.009788 -1.267206)
					)
				)
			)
		)
		(zone
			(layers "F.Cu" "B.Cu" "In1.Cu" "In2.Cu" "In3.Cu" "In4.Cu" "In5.Cu" "In6.Cu"
				"In7.Cu" "In8.Cu" "In9.Cu" "In10.Cu" "In11.Cu" "In12.Cu" "In13.Cu" "In14.Cu"
				"In15.Cu" "In16.Cu"
			)
			(hatch none 0.5)
			(connect_pads
				(clearance 0)
			)
			(min_thickness 0.25)
			(keepout
				(tracks not_allowed)
				(vias allowed)
				(pads allowed)
				(copperpour not_allowed)
				(footprints allowed)
			)
			(placement
				(enabled no)
				(sheetname "")
			)
			(fill
				(thermal_gap 0.5)
				(thermal_bridge_width 0.5)
				(island_removal_mode 0)
			)
			(polygon
				(pts
					(arc
						(start 313.009788 1.272794)
						(mid 311.155588 1.272794)
						(end 313.009788 1.272794)
					)
				)
			)
		)
		(zone
			(layers "F.Cu" "B.Cu" "In1.Cu" "In2.Cu" "In3.Cu" "In4.Cu" "In5.Cu" "In6.Cu"
				"In7.Cu" "In8.Cu" "In9.Cu" "In10.Cu" "In11.Cu" "In12.Cu" "In13.Cu" "In14.Cu"
				"In15.Cu" "In16.Cu"
			)
			(hatch none 0.5)
			(connect_pads
				(clearance 0)
			)
			(min_thickness 0.25)
			(keepout
				(tracks not_allowed)
				(vias allowed)
				(pads allowed)
				(copperpour not_allowed)
				(footprints allowed)
			)
			(placement
				(enabled no)
				(sheetname "")
			)
			(fill
				(thermal_gap 0.5)
				(thermal_bridge_width 0.5)
				(island_removal_mode 0)
			)
			(polygon
				(pts
					(arc
						(start 319.359788 -1.267206)
						(mid 317.505588 -1.267206)
						(end 319.359788 -1.267206)
					)
				)
			)
		)
		(zone
			(layers "F.Cu" "B.Cu" "In1.Cu" "In2.Cu" "In3.Cu" "In4.Cu" "In5.Cu" "In6.Cu"
				"In7.Cu" "In8.Cu" "In9.Cu" "In10.Cu" "In11.Cu" "In12.Cu" "In13.Cu" "In14.Cu"
				"In15.Cu" "In16.Cu"
			)
			(hatch none 0.5)
			(connect_pads
				(clearance 0)
			)
			(min_thickness 0.25)
			(keepout
				(tracks not_allowed)
				(vias allowed)
				(pads allowed)
				(copperpour not_allowed)
				(footprints allowed)
			)
			(placement
				(enabled no)
				(sheetname "")
			)
			(fill
				(thermal_gap 0.5)
				(thermal_bridge_width 0.5)
				(island_removal_mode 0)
			)
			(polygon
				(pts
					(arc
						(start 319.359788 1.272794)
						(mid 317.505588 1.272794)
						(end 319.359788 1.272794)
					)
				)
			)
		)
	)
)
